P  JOB   G:/<user>/9051_F0T_Panel_BD_Front_D_v02_20221209_1310.brd                 
P  CODE  00                                                                     
P  UNITS CUST 0                                                                 
P  TITLE G:/<user>/9051_F0T_Panel_BD_Front_D_v02_20221209_1310.brd                 
P  NUM   001                                                                    
P  REV   A                                                                      
P  VER IPC-D-356A                                                               
C                                                                               
C  IPC-D-356 Ouptut File from Allegro                                           
C  IPC File Date: Mon Dec 12 15:53:00 2022                                      
C                                                                               
C                                                                               
C  Board File:             9051_F0T_Panel_BD_Front_D_v02_20221209_1310.brd      
C  Design Rule Status:     UP TO DATE                                           
C  Unit of Measure:        mils                                                 
C  Decimal Place Accuracy: 2                                                    
C  Number of etch Layers:  4                                                    
C  Board Thickness(mils):  63.000000                                            
C  Drawing Extents(mils):  -498819  -506299  4701181  5193701                   
C                                                                               
C                                                                               
C  BOARD LAYER INFORMATION                                                      
C                                                                               
C     Layer      Layer            Layer             Film  Layer                 
C     Name       Material         Type              Type  Number                
C  ---------------------------------------------------------                    
C  TOP           COPPER           CONDUCTOR         POS     1                   
C  GND           COPPER           PLANE             NEG     2                   
C  GND1          COPPER           PLANE             NEG     3                   
C  BOTTOM        COPPER           CONDUCTOR         POS     4                   
C                                                                               
C                                                                               
C  PADSTACK INFORMATION                                                         
C                                                                               
C     Padstack          First     Last                                          
C     Name              Layer     Layer     Width     Height                    
C  ---------------------------------------------------------                    
C  C41D41N              TOP       BOTTOM         7100      7100                 
C  SMD85X156_CUT_NPM    TOP       TOP            8900     16000                 
C  SMD12X20_NPM         TOP       TOP            1600      2400                 
C  C48D32_T6_0          TOP       BOTTOM         6200      6200                 
C  S48D32_T6_0          TOP       BOTTOM         6200      6200                 
C  C54D38_T2            TOP       BOTTOM         6800      6800                 
C  S54D38_T2            TOP       BOTTOM         6800      6800                 
C  OB52X103D32X83       TOP       BOTTOM         6200     11300                 
C  OB52X75D32X56        TOP       BOTTOM         6200      8600                 
C  S44D28               TOP       BOTTOM         5800      5800                 
C  C44D28               TOP       BOTTOM         5800      5800                 
C  C119D119N            TOP       BOTTOM        14900     14900                 
C  SMD18X20             TOP       TOP            2200      2400                 
C  SMD44X54             TOP       TOP            4800      5800                 
C  RE-R_0824-2          TOP       TOP            2384      2368                 
C  RE-L_0824-2          TOP       TOP            2384      2368                 
C  SMD24X52             TOP       TOP            2800      5600                 
C  TC785CC25_O          TOP       BOTTOM         8700      8700                 
C  TC395CC25_O          TOP       BOTTOM         4800      4800                 
C  SMD24X56             TOP       TOP            2800      6000                 
C  SMD28X40_PM24X36     TOP       TOP            3200      4400                 
C  SMD24X28_PM20X24     TOP       TOP            2800      3200                 
C  SMD24X38             TOP       TOP            2800      4200                 
C  SMD16X54             TOP       TOP            2000      5800                 
C  SMD24X54             TOP       TOP            2800      5800                 
C  SMD24X32             TOP       TOP            2800      3600                 
C  SMD40X56             TOP       TOP            4400      6000                 
C  SMD17X24             TOP       TOP            2100      2800                 
C  SMD14X36             TOP       TOP            1800      4000                 
C  C85D67_SM85_NPM      TOP       BOTTOM         9700      9700                 
C  C42D26_T1-96         TOP       BOTTOM         5600      5600                 
C  C52D52N_T1-96        TOP       BOTTOM         8200      8200                 
C  SMD15X53             TOP       TOP            1900      5700                 
C  C125D125N_T2-0       TOP       BOTTOM        15500     15500                 
C  C158D158N            TOP       BOTTOM        18800     18800                 
C  GHC30D22_NTH         TOP       BOTTOM         4200      4200                 
C  SMD40X50             TOP       TOP            4400      5400                 
C  SMD28X32             TOP       TOP            3200      3600                 
C  VT20D10B26           TOP       BOTTOM         7502      7500                 
C  VT20D10T30           TOP       BOTTOM         7502      7500                 
C  VIA20D10             TOP       BOTTOM         3000      3000                 
C  SPD_C125                                     12500     12500                 
C  SMDC39M118           TOP       TOP           11800     11800                 
C  TP26B                BOTTOM    BOTTOM         7500      7500                 
C  TP30T                TOP       TOP            7500      7500                 
C                                                                               
C                                                                               
C  ****************************************                                     
C     Name mapping for long Signal names                                        
C  ****************************************                                     
C                                                                               
P  NNAMEm0000 DELTA_L_85_10INCH_TOP_DN                                          
P  NNAMEm0001 DELTA_L_85_10INCH_TOP_DP                                          
P  NNAMEm0002 DELTA_L_85_5INCH_TOP_DN                                           
P  NNAMEm0003 DELTA_L_85_5INCH_TOP_DP                                           
P  NNAMEm0004 UART_DEBUG_R_RX                                                   
P  NNAMEm0005 UART_DEBUG_R_TX                                                   
P  NNAMEm0006 SMB_IO_DEBUG_CARD_SDA                                             
P  NNAMEm0007 SMB_IO_DEBUG_CARD_SCL                                             
P  NNAMEm0008 SYSTEM_FAULT_ID_LED_R1_N                                          
P  NNAMEm0009 TDR_DIFF_85_TOP_DP                                                
P  NNAMEm0010 TDR_SE_50_OHM_TOP                                                 
P  NNAMEm0011 THERMAL_ADDR_A2                                                   
P  NNAMEm0012 TDR_DIFF_85_TOP_DN                                                
P  NNAMEm0013 TDR_SE_50_OHM_BOT                                                 
P  NNAMEm0014 THERMAL_ADDR_A1                                                   
P  NNAMEm0015 THERMAL_ADDR_A0                                                   
P  NNAMEm0016 SYSTEM_FAULT_ID_LED                                               
P  NNAMEm0017 SYSTEM_FAULT_ID_LED_R2_N                                          
P  NNAMEm0018 PRSNT_DBV2_SLIMSAS                                                
P  NNAMEm0019 PRSNT_DBV2_USB_N                                                  
P  NNAMEm0020 SYSTEM_FAULT_ID_LED_R1                                            
P  NNAMEm0021 FM_PFR_LED_BLUE_R                                                 
P  NNAMEm0022 FM_PFR_LED_BLUE_R_N                                               
P  NNAMEm0023 FM_PFR_LED_AMBER_R                                                
P  NNAMEm0024 FM_PFR_LED_AMBER_R_N                                              
P  NNAMEm0025 FM_PFR_LED_BLUE_N                                                 
P  NNAMEm0026 FM_PFR_LED_AMBER_N                                                
C                                                                               
C  ****************************************                                     
C      SIGNAL PINS & VIAS ON THE BOARD                                          
C  ****************************************                                     
C                                                                               
327m0000            J7    -2          A01X+037402Y+060775X0120Y0200R180 S1      
327m0000            J8    -1          A01X+037402Y+033094X0120Y0200     S1      
327m0001            J7    -1          A01X+037598Y+060775X0120Y0200R180 S1      
327m0001            J8    -2          A01X+037598Y+033094X0120Y0200     S1      
327m0002            J5    -1          A01X+034452Y+043475X0120Y0200     S1      
327m0002            J6    -2          A01X+034452Y+060775X0120Y0200R180 S1      
327m0003            J5    -2          A01X+034648Y+043475X0120Y0200     S1      
327m0003            J6    -1          A01X+034648Y+060775X0120Y0200R180 S1      
317GND1             VIA   -    MD0100PA00X+036996Y+033088X0200Y    R090 S0      
317GND1             VIA   -    MD0100PA00X+036866Y+032461X0200Y    R090 S0      
317GND1             VIA   -    MD0100PA00X+037117Y+032459X0200Y    R090 S0      
317GND1             VIA   -    MD0100PA00X+037918Y+032461X0200Y    R270 S0      
317GND1             VIA   -    MD0100PA00X+038170Y+032462X0200Y    R270 S0      
317GND1             VIA   -    MD0100PA00X+037643Y+032461X0200Y    R270 S0      
317GND1             VIA   -    MD0100PA00X+037392Y+032459X0200Y    R270 S0      
317GND1             VIA   -    MD0100PA00X+038171Y+032789X0200Y    R270 S0      
317GND1             VIA   -    MD0100PA00X+037920Y+032787X0200Y    R270 S0      
317GND1             VIA   -    MD0100PA00X+036867Y+032787X0200Y    R270 S0      
317GND1             VIA   -    MD0100PA00X+037118Y+032789X0200Y    R270 S0      
327GND1             J8    -3   M      A01X+037500Y+032769X0850Y1560R090 S1      
317GND1             VIA   -    MD0100PA00X+038049Y+033088X0200Y    R090 S0      
317GND1             VIA   -    MD0100PA00X+034046Y+043470X0200Y    R090 S0      
317GND1             VIA   -    MD0100PA00X+033916Y+042842X0200Y    R090 S0      
317GND1             VIA   -    MD0100PA00X+034167Y+042840X0200Y    R090 S0      
317GND1             VIA   -    MD0100PA00X+034968Y+042842X0200Y    R270 S0      
317GND1             VIA   -    MD0100PA00X+035220Y+042844X0200Y    R270 S0      
317GND1             VIA   -    MD0100PA00X+034693Y+042842X0200Y    R270 S0      
317GND1             VIA   -    MD0100PA00X+034442Y+042840X0200Y    R270 S0      
317GND1             VIA   -    MD0100PA00X+035221Y+043170X0200Y    R270 S0      
317GND1             VIA   -    MD0100PA00X+034970Y+043169X0200Y    R270 S0      
317GND1             VIA   -    MD0100PA00X+033917Y+043169X0200Y    R270 S0      
317GND1             VIA   -    MD0100PA00X+034168Y+043170X0200Y    R270 S0      
327GND1             J5    -3   M      A01X+034550Y+043150X0850Y1560R090 S1      
317GND1             VIA   -    MD0100PA00X+035099Y+043470X0200Y    R090 S0      
317GND1             VIA   -    MD0100PA00X+038004Y+060780X0200Y    R270 S0      
317GND1             VIA   -    MD0100PA00X+038134Y+061408X0200Y    R270 S0      
317GND1             VIA   -    MD0100PA00X+037883Y+061410X0200Y    R270 S0      
317GND1             VIA   -    MD0100PA00X+037082Y+061408X0200Y    R090 S0      
317GND1             VIA   -    MD0100PA00X+036830Y+061406X0200Y    R090 S0      
317GND1             VIA   -    MD0100PA00X+037357Y+061408X0200Y    R090 S0      
317GND1             VIA   -    MD0100PA00X+037608Y+061410X0200Y    R090 S0      
317GND1             VIA   -    MD0100PA00X+036829Y+061080X0200Y    R090 S0      
317GND1             VIA   -    MD0100PA00X+037080Y+061081X0200Y    R090 S0      
317GND1             VIA   -    MD0100PA00X+038133Y+061081X0200Y    R090 S0      
317GND1             VIA   -    MD0100PA00X+037882Y+061080X0200Y    R090 S0      
327GND1             J7    -3   M      A01X+037500Y+061100X0850Y1560R270 S1      
317GND1             VIA   -    MD0100PA00X+036951Y+060780X0200Y    R270 S0      
317GND1             VIA   -    MD0100PA00X+034001Y+060780X0200Y    R270 S0      
317GND1             VIA   -    MD0100PA00X+034932Y+061080X0200Y    R090 S0      
317GND1             VIA   -    MD0100PA00X+035183Y+061081X0200Y    R090 S0      
317GND1             VIA   -    MD0100PA00X+034658Y+061410X0200Y    R090 S0      
317GND1             VIA   -    MD0100PA00X+034407Y+061408X0200Y    R090 S0      
317GND1             VIA   -    MD0100PA00X+034130Y+061081X0200Y    R090 S0      
317GND1             VIA   -    MD0100PA00X+033879Y+061080X0200Y    R090 S0      
317GND1             VIA   -    MD0100PA00X+034132Y+061408X0200Y    R090 S0      
317GND1             VIA   -    MD0100PA00X+033880Y+061406X0200Y    R090 S0      
317GND1             VIA   -    MD0100PA00X+034933Y+061410X0200Y    R270 S0      
317GND1             VIA   -    MD0100PA00X+035184Y+061408X0200Y    R270 S0      
317GND1             VIA   -    MD0100PA00X+035054Y+060780X0200Y    R270 S0      
327GND1             J6    -3   M      A01X+034550Y+061100X0850Y1560R270 S1      
327SMB_SWB_SDA      VIA   -    M      A01X+008357Y+025607X0300Y         S1      
327SMB_SWB_SDA      R68   -1          A01X+008150Y+025108X0198Y0197R270 S1      
327SMB_SWB_SDA      J1    -B12        A01X+008130Y+027480X0150Y0530     S1      
327SMB_SWB_SCL      VIA   -    M      A01X+008850Y+026200X0300Y         S1      
327SMB_SWB_SCL      R67   -1          A01X+008550Y+025108X0198Y0197R270 S1      
327SMB_SWB_SCL      J1    -B11        A01X+008366Y+027480X0150Y0530     S1      
317m0004            J2    -9    D0280PA00X+010197Y+008398X0440Y         S3      
327m0004            R66   -1          A01X+009092Y+012000X0198Y0197     S1      
327m0004            U10   -3   M      A01X+009056Y+011424X0240Y0280R090 S1      
317m0005            J2    -8    D0280PA00X+010197Y+007610X0440Y         S3      
317m0005            VIA   -    MD0100PA00X+009250Y+012600X0200Y         S0      
327m0005            U10   -2   M      A01X+009844Y+011424X0240Y0280R090 S1      
317m0005            VIA   -    MD0100PA00X+008031Y+013874X0200Y         S0      
327m0005            R65   -1          A01X+007750Y+024792X0198Y0197R090 S1      
327m0005            VIA   -    M      A01X+007250Y+025000X0300Y         S1      
327UART_DEBUG_RX    VIA   -    M      A01X+006126Y+025400X0300Y         S1      
327UART_DEBUG_RX    R66   -2          A01X+009408Y+012000X0198Y0197     S1      
317UART_DEBUG_RX    VIA   -    MD0100PA00X+007834Y+013600X0200Y         S0      
317UART_DEBUG_RX    VIA   -    MD0100PA00X+008850Y+012350X0200Y         S0      
327UART_DEBUG_RX    J1    -B15        A01X+007421Y+027480X0150Y0530     S1      
327UART_DEBUG_TX    VIA   -    M      A01X+008250Y+026200X0300Y         S1      
327UART_DEBUG_TX    R65   -2          A01X+007750Y+025108X0198Y0197R090 S1      
327UART_DEBUG_TX    J1    -B14        A01X+007658Y+027480X0150Y0530     S1      
317m0006            J2    -6    D0280PA00X+010197Y+006035X0440Y         S3      
327m0006            U11   -3   M      A01X+007076Y+007256X0240Y0280R180 S1      
327m0006            R46   -2          A01X+006742Y+009900X0198Y0197R180 S1      
327m0006            R49   -1   M      A01X+006742Y+009500X0198Y0197     S1      
317m0007            J2    -5    D0280PA00X+010197Y+005248X0440Y         S3      
327m0007            R48   -1          A01X+006742Y+009100X0198Y0197     S1      
327m0007            R47   -2   M      A01X+006742Y+008700X0198Y0197R180 S1      
327m0007            U11   -2   M      A01X+007076Y+008044X0240Y0280R180 S1      
327SMB_EXP_SCL      U5    -22         A01X+005952Y+023696X0160Y0540R270 S1      
327SMB_EXP_SCL      R16   -2          A01X+007092Y+023550X0198Y0197R180 S1      
327SMB_EXP_SCL      VIA   -    M      A01X+006600Y+023450X0300Y         S1      
327SMB_EXP_SDA      U5    -23         A01X+005952Y+023952X0160Y0540R270 S1      
327SMB_EXP_SDA      R17   -2          A01X+007092Y+023950X0198Y0197R180 S1      
327SMB_EXP_SDA      VIA   -    M      A01X+006600Y+023950X0300Y         S1      
327m0008            R7    -2          A01X+003660Y+009850X0280Y0320R090 S1      
327m0008            VIA   -    M      A01X+003100Y+010100X0300Y         S1      
327m0008            R6    -2   M      A01X+003592Y+010350X0198Y0197R180 S1      
327m0008            U3    -D          A01X+002565Y+010100X0240Y0320R270 S1      
327NCP380_FLT_N     VIA   -    M      A01X+013750Y+010700X0300Y         S1      
327NCP380_FLT_N     U7    -4          A01X+013043Y+011276X0240Y0380R090 S1      
327NCP380_FLT_N     R41   -2          A01X+014292Y+010800X0198Y0197R180 S1      
327NCP380_ILIM      VIA   -    M      A01X+013300Y+010400X0300Y         S1      
327NCP380_ILIM      R42   -1          A01X+014292Y+010400X0198Y0197     S1      
327NCP380_ILIM      U7    -5          A01X+013043Y+011650X0240Y0380R090 S1      
327NCO380_EN        VIA   -    M      A01X+013750Y+010000X0300Y         S1      
327NCO380_EN        R40   -2          A01X+014292Y+010000X0198Y0197R180 S1      
327NCO380_EN        U7    -3          A01X+012157Y+011276X0240Y0380R090 S1      
327PWR_LED_R1_N     R11   -1          A01X+003660Y+010950X0280Y0320R270 S1      
327PWR_LED_R1_N     R10   -2   M      A01X+003592Y+011450X0198Y0197R180 S1      
327PWR_LED_R1_N     VIA   -    M      A01X+003100Y+011200X0300Y         S1      
327PWR_LED_R1_N     U4    -D          A01X+002565Y+011200X0240Y0320R270 S1      
317PWR_LED_R2_N     D3    -C    D0320PA00X+004394Y+002008X0480Y         S3      
327PWR_LED_R2_N     VIA   -    M      A01X+004450Y+010400X0300Y         S1      
327PWR_LED_R2_N     R11   -2          A01X+004240Y+010950X0280Y0320R270 S1      
317SMB_TMP75_SCL    VIA   -    MD0100PA00X+008100Y+009100X0200Y         S0      
327SMB_TMP75_SCL    U6    -2          A01X+012298Y+001672X0240Y0520R270 S1      
317SMB_TMP75_SCL    VIA   -    M      A01X+010981Y+001672X0200Y         S2      
017SMB_TMP75_SCL    VIA   -    M      A04X+010981Y+001672X0260Y         S2      
017SMB_TMP75_SCL          -    MD0100PA00X+010981Y+001672                       
327SMB_TMP75_SCL    R36   -2   M      A01X+007858Y+009100X0198Y0197     S1      
327SMB_TMP75_SCL    R30   -2          A01X+007858Y+008700X0198Y0197     S1      
317m0009            X2    -4    D0098PA00X+037020Y+009300X0395Y    R270 S3      
317m0009            X1    -1    D0098PA00X+037020Y+024762X0395Y    R090 S3      
317GND_TDR          X1    -2   MD0098PA00X+037020Y+025762X0785Y    R090 S3      
317GND_TDR          X1    -3   MD0098PA00X+038020Y+025762X0785Y    R090 S3      
317GND_TDR          X2    -2   MD0098PA00X+038020Y+008300X0785Y    R270 S3      
317GND_TDR          X2    -3   MD0098PA00X+037020Y+008300X0785Y    R270 S3      
317GND_TDR          J3    -1   MD0670PA00X+034703Y+024771X0850Y    R180 S3      
317GND_TDR          J4    -1   MD0670PA00X+034494Y+009173X0850Y         S3      
327THERMAL_OS       R29   -2          A01X+006500Y+007592X0198Y0197R270 S1      
317THERMAL_OS       VIA   -    MD0100PA00X+006500Y+007350X0200Y         S0      
317THERMAL_OS       VIA   -    M      A01X+011196Y+001172X0200Y         S2      
017THERMAL_OS       VIA   -    M      A04X+011196Y+001172X0260Y         S2      
017THERMAL_OS             -    MD0100PA00X+011196Y+001172                       
327THERMAL_OS       U6    -3          A01X+012298Y+001172X0240Y0520R270 S1      
317SMB_TMP75_SDA    VIA   -    MD0100PA00X+008100Y+009500X0200Y         S0      
327SMB_TMP75_SDA    U6    -1          A01X+012298Y+002172X0240Y0520R270 S1      
317SMB_TMP75_SDA    VIA   -    M      A01X+010695Y+002172X0200Y         S2      
017SMB_TMP75_SDA    VIA   -    M      A04X+010695Y+002172X0260Y         S2      
017SMB_TMP75_SDA          -    MD0100PA00X+010695Y+002172                       
327SMB_TMP75_SDA    R31   -2          A01X+007858Y+009900X0198Y0197     S1      
327SMB_TMP75_SDA    R35   -2   M      A01X+007858Y+009500X0198Y0197     S1      
317m0010            J3    -2    D0670PA00X+035203Y+023452X0850Y    R180 S3      
317m0010            J3    -3    D0670PA00X+034203Y+023452X0850Y    R180 S3      
317m0011            VIA   -    M      A01X+012750Y+000672X0200Y         S2      
017m0011            VIA   -    M      A04X+012750Y+000672X0260Y         S2      
017m0011                  -    MD0100PA00X+012750Y+000672                       
327m0011            U6    -5          A01X+014385Y+000672X0240Y0520R270 S1      
317m0011            VIA   -    MD0100PA00X+013700Y+009200X0200Y         S0      
327m0011            R34   -2   M      A01X+014292Y+009200X0198Y0197R180 S1      
327m0011            R39   -1          A01X+014292Y+009600X0198Y0197     S1      
317m0012            X2    -1    D0098PA00X+038020Y+009300X0395Y    R270 S3      
317m0012            X1    -4    D0098PA00X+038020Y+024762X0395Y    R090 S3      
317P5V_STBY_DEBUG   J2    -1   MD0280PA00X+009488Y+008201X0440Y0440     S3      
327P5V_STBY_DEBUG   U10   -4          A01X+009056Y+010676X0240Y0280R090 S1      
327P5V_STBY_DEBUG   U11   -4          A01X+007824Y+007256X0240Y0280R180 S1      
327P5V_STBY_DEBUG   VIA   -           A04X+011700Y+012250X0260Y         S2      
327P5V_STBY_DEBUG   VIA   -           A04X+013450Y+010500X0260Y         S2      
327P5V_STBY_DEBUG   VIA   -           A04X+009800Y+009900X0260Y         S2      
317P5V_STBY_DEBUG   VIA   -    MD0100PA00X+010697Y+006833X0200Y         S0      
327P5V_STBY_DEBUG   U8    -4          A01X+012051Y+007564X0240Y0280R090 S1      
317P5V_STBY_DEBUG   VIA   -    MD0100PA00X+010697Y+006583X0200Y         S0      
317P5V_STBY_DEBUG   VIA   -    M      A01X+013450Y+011900X0200Y         S2      
017P5V_STBY_DEBUG   VIA   -    M      A04X+013450Y+011900X0260Y         S2      
017P5V_STBY_DEBUG         -    MD0100PA00X+013450Y+011900                       
317P5V_STBY_DEBUG   VIA   -    MD0100PA00X+013450Y+012250X0200Y         S0      
327P5V_STBY_DEBUG   C16   -1          A01X+013800Y+013450X0400Y0500R180 S1      
327P5V_STBY_DEBUG   C12   -1          A01X+013800Y+012750X0400Y0500R180 S1      
327P5V_STBY_DEBUG   C14   -1          A01X+013100Y+013450X0400Y0500     S1      
327P5V_STBY_DEBUG   C15   -1          A01X+013100Y+012750X0400Y0500     S1      
327P5V_STBY_DEBUG   U7    -6          A01X+013043Y+012024X0240Y0380R090 S1      
317P5V_STBY_DEBUG   VIA   -    MD0100PA00X+013450Y+012600X0200Y         S0      
317P5V_STBY_DEBUG   VIA   -    MD0100PA00X+013450Y+012950X0200Y         S0      
317P5V_STBY_DEBUG   VIA   -    MD0100PA00X+013450Y+013300X0200Y         S0      
317P5V_STBY_DEBUG   VIA   -    MD0100PA00X+013450Y+013650X0200Y         S0      
327P5V_STBY_DEBUG   C10   -1          A01X+013800Y+012050X0400Y0500R180 S1      
327P5V_STBY_DEBUG   C9    -1          A01X+013800Y+011350X0400Y0500R180 S1      
317m0013            J4    -2    D0670PA00X+033994Y+010491X0850Y         S3      
317m0013            J4    -3    D0670PA00X+034994Y+010491X0850Y         S3      
327PWR_LED          VIA   -    M      A01X+006600Y+022950X0300Y         S1      
327PWR_LED          R15   -1          A01X+007092Y+022350X0198Y0197     S1      
327PWR_LED          U5    -20         A01X+005952Y+023184X0160Y0540R270 S1      
327m0014            U6    -6          A01X+014385Y+001172X0240Y0520R270 S1      
317m0014            VIA   -    M      A01X+013950Y+001050X0200Y         S2      
017m0014            VIA   -    M      A04X+013950Y+001050X0260Y         S2      
017m0014                  -    MD0100PA00X+013950Y+001050                       
317m0014            VIA   -    MD0100PA00X+013700Y+008800X0200Y         S0      
327m0014            R33   -2          A01X+014292Y+008400X0198Y0197R180 S1      
327m0014            R38   -1   M      A01X+014292Y+008800X0198Y0197     S1      
327m0015            U6    -7          A01X+014385Y+001672X0240Y0520R270 S1      
317m0015            VIA   -    M      A01X+013200Y+001050X0200Y         S2      
017m0015            VIA   -    M      A04X+013200Y+001050X0260Y         S2      
017m0015                  -    MD0100PA00X+013200Y+001050                       
317m0015            VIA   -    MD0100PA00X+013700Y+008450X0200Y         S0      
327m0015            R32   -2          A01X+014292Y+007600X0198Y0197R180 S1      
327m0015            R37   -1   M      A01X+014292Y+008000X0198Y0197     S1      
327m0016            VIA   -    M      A01X+006600Y+022450X0300Y         S1      
327m0016            R14   -1          A01X+007092Y+021950X0198Y0197     S1      
327m0016            U5    -19         A01X+005952Y+022928X0160Y0540R270 S1      
317m0017            D2    -C    D0320PA00X+002032Y+002008X0480Y         S3      
327m0017            VIA   -    M      A01X+004240Y+009300X0300Y         S1      
327m0017            R7    -1          A01X+004240Y+009850X0280Y0320R090 S1      
317m0017            VIA   -    MD0100PA00X+004240Y+008650X0200Y         S0      
327SMB_FRU_SCL      R53   -2   M      A01X+006092Y+018950X0198Y0197R180 S1      
327SMB_FRU_SCL      R59   -2          A01X+006092Y+018550X0198Y0197R180 S1      
327SMB_FRU_SCL      VIA   -    M      A01X+005600Y+019150X0300Y         S1      
327SMB_FRU_SCL      U9    -6          A01X+004943Y+019100X0240Y0560R270 S1      
327PD_FRU_A1        U9    -2          A01X+002857Y+019600X0240Y0560R270 S1      
327PD_FRU_A1        R57   -2   M      A01X+001708Y+019600X0198Y0197     S1      
327PD_FRU_A1        R62   -1          A01X+001708Y+019200X0198Y0197R180 S1      
327PD_FRU_A1        VIA   -    M      A01X+002200Y+019600X0300Y         S1      
327PD_FRU_A0        U9    -1          A01X+002857Y+020100X0240Y0560R270 S1      
327PD_FRU_A0        VIA   -    M      A01X+002200Y+020100X0300Y         S1      
327PD_FRU_A0        R58   -2          A01X+001708Y+020400X0198Y0197     S1      
327PD_FRU_A0        R63   -2   M      A01X+001708Y+020000X0198Y0197     S1      
327PD_FRU_WP        R55   -2   M      A01X+006092Y+019350X0198Y0197R180 S1      
327PD_FRU_WP        R64   -1          A01X+006092Y+019750X0198Y0197     S1      
327PD_FRU_WP        VIA   -    M      A01X+005600Y+019650X0300Y         S1      
327PD_FRU_WP        U9    -7          A01X+004943Y+019600X0240Y0560R270 S1      
327SMB_FRU_SDA      VIA   -    M      A01X+005600Y+018600X0300Y         S1      
327SMB_FRU_SDA      U9    -5          A01X+004943Y+018600X0240Y0560R270 S1      
327SMB_FRU_SDA      R54   -2          A01X+006092Y+017750X0198Y0197R180 S1      
327SMB_FRU_SDA      R60   -2   M      A01X+006092Y+018150X0198Y0197R180 S1      
327PD_FRU_A2        U9    -3          A01X+002857Y+019100X0240Y0560R270 S1      
327PD_FRU_A2        R56   -2   M      A01X+001708Y+018800X0198Y0197     S1      
327PD_FRU_A2        R61   -1          A01X+001708Y+018400X0198Y0197R180 S1      
327PD_FRU_A2        VIA   -    M      A01X+002200Y+019000X0300Y         S1      
327P3V3_STBY        VIA   -           A04X+005500Y+027600X0260Y         S2      
327P3V3_STBY        VIA   -           A04X+010150Y+027750X0260Y         S2      
327P3V3_STBY        VIA   -           A04X+001250Y+011700X0260Y         S2      
317P3V3_STBY        VIA   -    MD0100PA00X+007542Y+010200X0200Y         S0      
327P3V3_STBY        R31   -1   M      A01X+007542Y+009900X0198Y0197     S1      
327P3V3_STBY        R46   -1   M      A01X+007058Y+009900X0198Y0197R180 S1      
317P3V3_STBY        VIA   -    MD0100PA00X+007850Y+011250X0200Y         S0      
317P3V3_STBY        VIA   -    MD0100PA00X+007850Y+011000X0200Y         S0      
327P3V3_STBY        R44   -1          A01X+005458Y+011000X0198Y0197R180 S1      
327P3V3_STBY        R45   -1          A01X+005950Y+010058X0198Y0197R270 S1      
327P3V3_STBY        R29   -1          A01X+006500Y+007908X0198Y0197R270 S1      
317P3V3_STBY        VIA   -    MD0100PA00X+007300Y+008700X0200Y         S0      
327P3V3_STBY        R30   -1          A01X+007542Y+008700X0198Y0197     S1      
327P3V3_STBY        R47   -1          A01X+007058Y+008700X0198Y0197R180 S1      
327P3V3_STBY        R9    -1          A01X+001042Y+011450X0198Y0197     S1      
317P3V3_STBY        VIA   -    MD0100PA00X+000800Y+011450X0200Y         S0      
317P3V3_STBY        VIA   -    MD0100PA00X+000800Y+010350X0200Y         S0      
327P3V3_STBY        R5    -1          A01X+001042Y+010350X0198Y0197     S1      
327P3V3_STBY        R40   -1          A01X+014608Y+010000X0198Y0197R180 S1      
317P3V3_STBY        VIA   -    MD0100PA00X+014850Y+010000X0200Y         S0      
327P3V3_STBY        R41   -1          A01X+014608Y+010800X0198Y0197R180 S1      
317P3V3_STBY        VIA   -    MD0100PA00X+014850Y+010800X0200Y         S0      
327P3V3_STBY        U9    -8          A01X+004943Y+020100X0240Y0560R270 S1      
327P3V3_STBY        R54   -1          A01X+006408Y+017750X0198Y0197R180 S1      
317P3V3_STBY        VIA   -    MD0100PA00X+006700Y+017750X0200Y         S0      
327P3V3_STBY        R55   -1          A01X+006408Y+019350X0198Y0197R180 S1      
317P3V3_STBY        VIA   -    MD0100PA00X+006650Y+019350X0200Y         S0      
317P3V3_STBY        VIA   -    M      A01X+006650Y+018950X0200Y         S2      
017P3V3_STBY        VIA   -    M      A04X+006650Y+018950X0260Y         S2      
017P3V3_STBY              -    MD0100PA00X+006650Y+018950                       
327P3V3_STBY        R53   -1          A01X+006408Y+018950X0198Y0197R180 S1      
317P3V3_STBY        VIA   -    MD0100PA00X+014850Y+009200X0200Y    R090 S0      
327P3V3_STBY        R34   -1          A01X+014608Y+009200X0198Y0197R180 S1      
317P3V3_STBY        VIA   -    M      A01X+014850Y+008400X0200Y    R270 S2      
017P3V3_STBY        VIA   -    M      A04X+014850Y+008400X0260Y    R270 S2      
017P3V3_STBY              -    MD0100PA00X+014850Y+008400                       
327P3V3_STBY        R33   -1          A01X+014608Y+008400X0198Y0197R180 S1      
327P3V3_STBY        R32   -1          A01X+014608Y+007600X0198Y0197R180 S1      
317P3V3_STBY        VIA   -    MD0100PA00X+014850Y+007600X0200Y         S0      
327P3V3_STBY        U6    -8          A01X+014385Y+002172X0240Y0520R270 S1      
327P3V3_STBY        C7    -1   M      A01X+012391Y+002721X0198Y0197R180 S1      
317P3V3_STBY        VIA   -    MD0100PA00X+012213Y+003022X0200Y         S0      
317P3V3_STBY        VIA   -    MD0100PA00X+007650Y+023150X0200Y         S0      
327P3V3_STBY        R20   -2          A01X+007408Y+023150X0198Y0197     S1      
327P3V3_STBY        C2    -1          A01X+007042Y+026550X0198Y0197     S1      
317P3V3_STBY        VIA   -    MD0100PA00X+007000Y+025800X0200Y         S0      
327P3V3_STBY        J1    -B17        A01X+006949Y+027480X0150Y0530     S1      
327P3V3_STBY        C1    -1          A01X+007060Y+026100X0280Y0320R270 S1      
317P3V3_STBY        VIA   -    MD0100PA00X+007250Y+025800X0200Y         S0      
317P3V3_STBY        VIA   -    MD0100PA00X+001950Y+024150X0200Y         S0      
327P3V3_STBY        R19   -2          A01X+002192Y+024150X0198Y0197R180 S1      
317P3V3_STBY        VIA   -    MD0100PA00X+001950Y+023350X0200Y         S0      
327P3V3_STBY        R18   -2          A01X+002192Y+023350X0198Y0197R180 S1      
327P3V3_STBY        R23   -1          A01X+002192Y+022550X0198Y0197     S1      
317P3V3_STBY        VIA   -    MD0100PA00X+001950Y+022550X0200Y         S0      
317P3V3_STBY        VIA   -    MD0100PA00X+006592Y+024700X0200Y         S0      
327P3V3_STBY        C5    -1   M      A01X+006592Y+024450X0198Y0197     S1      
327P3V3_STBY        U5    -24         A01X+005952Y+024247X0240Y0540R270 S1      
327P3V3_STBY        R22   -1          A01X+002192Y+021750X0198Y0197     S1      
317P3V3_STBY        VIA   -    MD0100PA00X+001950Y+021750X0200Y         S0      
317P3V3_STBY        VIA   -    MD0100PA00X+001950Y+020950X0200Y         S0      
327P3V3_STBY        R21   -1          A01X+002192Y+020950X0198Y0197     S1      
327P3V3_STBY        C11   -1   M      A01X+005592Y+020150X0198Y0197     S1      
317P3V3_STBY        VIA   -    MD0100PA00X+005592Y+020400X0200Y         S0      
327P3V3_STBY        R58   -1          A01X+001392Y+020400X0198Y0197     S1      
317P3V3_STBY        VIA   -    MD0100PA00X+001150Y+020400X0200Y         S0      
317P3V3_STBY        VIA   -    MD0100PA00X+001150Y+018800X0200Y         S0      
327P3V3_STBY        R56   -1          A01X+001392Y+018800X0198Y0197     S1      
327P3V3_STBY        R57   -1          A01X+001392Y+019600X0198Y0197     S1      
317P3V3_STBY        VIA   -    MD0100PA00X+001150Y+019600X0200Y         S0      
327SMB_SCL          R36   -1          A01X+007542Y+009100X0198Y0197     S1      
327SMB_SCL          R48   -2          A01X+007058Y+009100X0198Y0197     S1      
327SMB_SCL          VIA   -    M      A01X+008100Y+023550X0300Y         S1      
327SMB_SCL          R16   -1          A01X+007408Y+023550X0198Y0197R180 S1      
327SMB_SCL          R67   -2          A01X+008550Y+024792X0198Y0197R270 S1      
317SMB_SCL          VIA   -    MD0100PA00X+007300Y+009100X0200Y         S0      
317SMB_SCL          VIA   -    MD0100PA00X+006650Y+018550X0200Y         S0      
327SMB_SCL          R59   -1          A01X+006408Y+018550X0198Y0197R180 S1      
317SMB_SCL          VIA   -    MD0100PA00X+007600Y+012650X0200Y         S0      
317SMB_SCL          VIA   -    MD0100PA00X+007650Y+023550X0200Y         S0      
327SMB_SDA          VIA   -    M      A01X+008150Y+024300X0300Y         S1      
327SMB_SDA          R68   -2          A01X+008150Y+024792X0198Y0197R270 S1      
317SMB_SDA          VIA   -    MD0100PA00X+007600Y+012300X0200Y         S0      
317SMB_SDA          VIA   -    MD0100PA00X+006650Y+018150X0200Y         S0      
317SMB_SDA          VIA   -    MD0100PA00X+007650Y+023950X0200Y         S0      
327SMB_SDA          R17   -1          A01X+007408Y+023950X0198Y0197R180 S1      
327SMB_SDA          R60   -1          A01X+006408Y+018150X0198Y0197R180 S1      
327SMB_SDA          R49   -2          A01X+007058Y+009500X0198Y0197     S1      
317SMB_SDA          VIA   -    MD0100PA00X+007300Y+009500X0200Y         S0      
327SMB_SDA          R35   -1          A01X+007542Y+009500X0198Y0197     S1      
327RST_SMB_N        VIA   -    M      A01X+005050Y+024900X0300Y         S1      
327RST_SMB_N        R13   -1          A01X+004558Y+024700X0198Y0197R180 S1      
327RST_SMB_N        J1    -B8         A01X+009075Y+027480X0150Y0530     S1      
327m0018            Q1    -3          A01X+005406Y+009226X0170Y0240     S1      
327m0018            J1    -B9         A01X+008839Y+027480X0150Y0530     S1      
327m0018            R45   -2          A01X+005950Y+009742X0198Y0197R270 S1      
317m0018            VIA   -    M      A01X+005950Y+009500X0200Y         S2      
017m0018            VIA   -    M      A04X+005950Y+009500X0260Y         S2      
017m0018                  -    MD0100PA00X+005950Y+009500                       
317m0018            VIA   -    MD0100PA00X+008350Y+012950X0200Y         S0      
327m0019            VIA   -    M      A01X+005150Y+010500X0300Y         S1      
327m0019            R44   -2          A01X+005142Y+011000X0198Y0197R180 S1      
327m0019            Q1    -5   M      A01X+005150Y+009974X0170Y0240     S1      
327m0019            Q1    -6          A01X+004894Y+009974X0170Y0240     S1      
327REV_ID<0>        U5    -11         A01X+003648Y+021648X0160Y0540R270 S1      
327REV_ID<0>        VIA   -    M      A01X+003000Y+021350X0300Y         S1      
327REV_ID<0>        R21   -2          A01X+002508Y+020950X0198Y0197     S1      
327REV_ID<0>        R26   -1   M      A01X+002508Y+021350X0198Y0197R180 S1      
327REV_ID<1>        U5    -10         A01X+003648Y+021904X0160Y0540R270 S1      
327REV_ID<1>        VIA   -    M      A01X+003000Y+021850X0300Y         S1      
327REV_ID<1>        R22   -2   M      A01X+002508Y+021750X0198Y0197     S1      
327REV_ID<1>        R27   -1          A01X+002508Y+022150X0198Y0197R180 S1      
327REV_ID<2>        U5    -9          A01X+003648Y+022160X0160Y0540R270 S1      
327REV_ID<2>        VIA   -    M      A01X+003000Y+022350X0300Y         S1      
327REV_ID<2>        R28   -1          A01X+002508Y+022950X0198Y0197R180 S1      
327REV_ID<2>        R23   -2   M      A01X+002508Y+022550X0198Y0197     S1      
317PRSNT_DBV2_USB   J2    -7    D0280PA00X+010197Y+006823X0440Y         S3      
317PRSNT_DBV2_USB   VIA   -    MD0100PA00X+010732Y+006318X0200Y         S0      
327PRSNT_DBV2_USB   R43   -2   M      A01X+005458Y+008350X0198Y0197     S1      
327PRSNT_DBV2_USB   R50   -1   M      A01X+005458Y+008750X0198Y0197R180 S1      
327PRSNT_DBV2_USB   Q1    -2          A01X+005150Y+009226X0170Y0240     S1      
317PCA9539_A0       VIA   -    M      A01X+006850Y+023150X0200Y         S2      
017PCA9539_A0       VIA   -    M      A04X+006850Y+023150X0260Y         S2      
017PCA9539_A0             -    MD0100PA00X+006850Y+023150                       
327PCA9539_A0       U5    -21         A01X+005952Y+023440X0160Y0540R270 S1      
327PCA9539_A0       R20   -1   M      A01X+007092Y+023150X0198Y0197     S1      
327PCA9539_A0       R25   -1          A01X+007092Y+022750X0198Y0197     S1      
327PCA9539_A1       VIA   -    M      A01X+003000Y+024150X0300Y         S1      
327PCA9539_A1       U5    -2          A01X+003648Y+023952X0160Y0540R270 S1      
327PCA9539_A1       R24   -1          A01X+002508Y+024550X0198Y0197R180 S1      
327PCA9539_A1       R19   -1   M      A01X+002508Y+024150X0198Y0197R180 S1      
327RST_SMB_R_N      R13   -2          A01X+004242Y+024700X0198Y0197R180 S1      
327RST_SMB_R_N      VIA   -    M      A01X+003000Y+023650X0300Y         S1      
327RST_SMB_R_N      U5    -3   M      A01X+003648Y+023696X0160Y0540R270 S1      
327RST_SMB_R_N      R18   -1          A01X+002508Y+023350X0198Y0197R180 S1      
327RST_SMB_R_N      C6    -1   M      A01X+002508Y+023750X0198Y0197R180 S1      
327PWR_LED_R1       R15   -2          A01X+007408Y+022350X0198Y0197     S1      
327PWR_LED_R1       VIA   -    M      A01X+007900Y+022350X0300Y         S1      
317PWR_LED_R1       VIA   -    MD0100PA00X+008350Y+013300X0200Y         S0      
317PWR_LED_R1       VIA   -    MD0100PA00X+005950Y+011796X0200Y         S0      
327PWR_LED_R1       R9    -2   M      A01X+001358Y+011450X0198Y0197     S1      
327PWR_LED_R1       R12   -1          A01X+001358Y+011050X0198Y0197R180 S1      
327PWR_LED_R1       U4    -G   M      A01X+001935Y+011456X0240Y0320R270 S1      
327m0020            VIA   -    M      A01X+001600Y+011950X0300Y         S1      
327m0020            R14   -2          A01X+007408Y+021950X0198Y0197     S1      
327m0020            R5    -2   M      A01X+001358Y+010350X0198Y0197     S1      
327m0020            R8    -1          A01X+001358Y+009950X0198Y0197R180 S1      
327m0020            U3    -G          A01X+001935Y+010356X0240Y0320R270 S1      
327USB2_DP          R52   -1          A01X+012612Y+009527X0180Y0200R090 S1      
327USB2_DP          L1    -4   M      A01X+012612Y+009727X0140Y0360     S1      
327USB2_DP          J1    -B2         A01X+010492Y+027480X0150Y0530     S1      
327USB2_DN          R51   -1          A01X+012278Y+009527X0180Y0200R090 S1      
327USB2_DN          L1    -1   M      A01X+012278Y+009727X0140Y0360     S1      
327USB2_DN          J1    -B3         A01X+010256Y+027480X0150Y0530     S1      
317P5V_STBY         D2    -A   MD0320PA00X+001032Y+002008X0480Y0480     S3      
317P5V_STBY         D3    -A    D0320PA00X+003394Y+002008X0480Y0480     S3      
317P5V_STBY         VIA   -    M      A01X+005200Y+008100X0200Y         S2      
017P5V_STBY         VIA   -    M      A04X+005200Y+008100X0260Y         S2      
017P5V_STBY               -    MD0100PA00X+005200Y+008100                       
327P5V_STBY         R43   -1          A01X+005142Y+008350X0198Y0197     S1      
317P5V_STBY         VIA   -    M      A01X+004104Y+011254X0200Y         S2      
017P5V_STBY         VIA   -    M      A04X+004104Y+011254X0260Y         S2      
017P5V_STBY               -    MD0100PA00X+004104Y+011254                       
327P5V_STBY         R10   -1          A01X+003908Y+011450X0198Y0197R180 S1      
317P5V_STBY         VIA   -    M      A01X+004150Y+010350X0200Y         S2      
017P5V_STBY         VIA   -    M      A04X+004150Y+010350X0260Y         S2      
017P5V_STBY               -    MD0100PA00X+004150Y+010350                       
327P5V_STBY         R6    -1          A01X+003908Y+010350X0198Y0197R180 S1      
327P5V_STBY         C13   -1          A01X+011492Y+013000X0198Y0197     S1      
327P5V_STBY         C8    -1          A01X+011492Y+012600X0198Y0197     S1      
327P5V_STBY         U7    -1          A01X+012157Y+012024X0240Y0380R090 S1      
317P5V_STBY         VIA   -    MD0100PA00X+011500Y+015050X0200Y         S0      
317P5V_STBY         VIA   -    MD0100PA00X+011500Y+014700X0200Y         S0      
317P5V_STBY         VIA   -    MD0100PA00X+011200Y+015050X0200Y         S0      
317P5V_STBY         VIA   -    MD0100PA00X+011200Y+014700X0200Y         S0      
327P5V_STBY         C4    -1          A01X+006308Y+026550X0198Y0197R180 S1      
327P5V_STBY         J1    -B18        A01X+006713Y+027480X0150Y0530     S1      
327P5V_STBY         C3    -1          A01X+006540Y+026100X0280Y0320R090 S1      
317P5V_STBY         VIA   -    MD0100PA00X+006650Y+025800X0200Y         S0      
317P5V_STBY         VIA   -    MD0100PA00X+006400Y+025800X0200Y         S0      
327P5V_STBY         J1    -A18        A01X+006713Y+028406X0150Y0530     S1      
317P5V_STBY         VIA   -    MD0100PA00X+006831Y+028820X0200Y    R180 S0      
327P5V_STBY         J1    -A17        A01X+006949Y+028406X0150Y0530     S1      
327P5V_STBY         J1    -A14        A01X+007658Y+028406X0150Y0530     S1      
317P5V_STBY         VIA   -    M      A01X+007539Y+028820X0200Y    R180 S2      
017P5V_STBY         VIA   -    M      A04X+007539Y+028820X0260Y    R180 S2      
017P5V_STBY               -    MD0100PA00X+007539Y+028820                       
327P5V_STBY         J1    -A15        A01X+007421Y+028406X0150Y0530     S1      
327P5V_STBY         J1    -A9         A01X+008839Y+028406X0150Y0530     S1      
317P5V_STBY         VIA   -    MD0100PA00X+008957Y+028820X0200Y    R180 S0      
327P5V_STBY         J1    -A8         A01X+009075Y+028406X0150Y0530     S1      
327P5V_STBY         J1    -A5         A01X+009784Y+028406X0150Y0530     S1      
317P5V_STBY         VIA   -    MD0100PA00X+009665Y+028820X0200Y    R180 S0      
327P5V_STBY         J1    -A6         A01X+009547Y+028406X0150Y0530     S1      
317P5V_STBY         VIA   -    MD0100PA00X+001032Y+001300X0200Y         S0      
317P5V_STBY         VIA   -    M      A01X+007256Y+004692X0200Y         S2      
017P5V_STBY         VIA   -    M      A04X+007256Y+004692X0260Y         S2      
017P5V_STBY               -    MD0100PA00X+007256Y+004692                       
327P5V_STBY         R3    -1          A01X+007676Y+004692X0440Y0540R090 S1      
317P5V_STBY         VIA   -    MD0100PA00X+006360Y+003419X0200Y         S0      
327P5V_STBY         R1    -1          A01X+006360Y+003710X0280Y0320R270 S1      
317GND              J2    -G2  MD0320PA00X+010910Y+004724X0520Y0750     S3      
317GND              J2    -G3  MD0320PA00X+008776Y+008937X0520Y0750     S3      
317GND              J2    -G1  MD0320PA00X+008776Y+004724X0520Y1030     S3      
317GND              J2    -G4  MD0320PA00X+010910Y+008937X0520Y1030     S3      
327GND              U10   -1          A01X+009844Y+010755X0280Y0400R180 S1      
317GND              J2    -4   MD0280PA00X+009488Y+005445X0440Y         S3      
317GND              D1    -2   MD0380PA00X+006748Y+002630X0540Y         S3      
317GND              VIA   -    MD0100PA00X+008450Y+009500X0200Y         S0      
317GND              VIA   -    MD0100PA00X+007050Y+017750X0200Y         S0      
317GND              VIA   -    MD0100PA00X+009900Y+006550X0200Y         S0      
317GND              VIA   -    MD0100PA00X+006600Y+011800X0200Y         S0      
317GND              VIA   -    MD0100PA00X+007000Y+013850X0200Y         S0      
317GND              VIA   -    MD0100PA00X+009450Y+012900X0200Y         S0      
317GND              VIA   -    MD0100PA00X+008150Y+012650X0200Y         S0      
317GND              VIA   -    MD0100PA00X+006250Y+005500X0200Y         S0      
317GND              H9    -2   MD0220PA00X+000922Y+005866X0300Y    R180 S3      
317GND              H9    -3   MD0220PA00X+001355Y+004820X0300Y    R180 S3      
317GND              H9    -4   MD0220PA00X+002402Y+004386X0300Y    R180 S3      
317GND              H9    -5   MD0220PA00X+003448Y+004820X0300Y    R180 S3      
317GND              H9    -6   MD0220PA00X+003881Y+005866X0300Y    R180 S3      
317GND              H9    -7   MD0220PA00X+003448Y+006912X0300Y    R180 S3      
317GND              H9    -8   MD0220PA00X+002402Y+007346X0300Y    R180 S3      
317GND              H9    -9   MD0220PA00X+001355Y+006912X0300Y    R180 S3      
317GND              VIA   -    M      A01X+009100Y+001850X0200Y         S2      
017GND              VIA   -    M      A04X+009100Y+001850X0260Y         S2      
017GND                    -    MD0100PA00X+009100Y+001850                       
317GND              VIA   -    M      A01X+009950Y+000900X0200Y         S2      
017GND              VIA   -    M      A04X+009950Y+000900X0260Y         S2      
017GND                    -    MD0100PA00X+009950Y+000900                       
317GND              VIA   -    MD0100PA00X+014822Y+004342X0200Y         S0      
317GND              VIA   -    MD0100PA00X+014471Y+003494X0200Y    R315 S0      
317GND              VIA   -    MD0100PA00X+013622Y+003142X0200Y    R270 S0      
317GND              VIA   -    MD0100PA00X+012774Y+003494X0200Y    R225 S0      
317GND              VIA   -    MD0100PA00X+012422Y+004342X0200Y    R180 S0      
317GND              VIA   -    MD0100PA00X+001398Y+027945X0200Y    R180 S0      
317GND              VIA   -    MD0100PA00X+001750Y+027096X0200Y    R225 S0      
317GND              VIA   -    MD0100PA00X+002598Y+026745X0200Y    R270 S0      
317GND              VIA   -    MD0100PA00X+003447Y+027096X0200Y    R315 S0      
317GND              VIA   -    MD0100PA00X+003798Y+027945X0200Y         S0      
327GND              R50   -2          A01X+005142Y+008750X0198Y0197R180 S1      
317GND              VIA   -    M      A01X+001600Y+010944X0200Y         S2      
017GND              VIA   -    M      A04X+001600Y+010944X0260Y         S2      
017GND                    -    MD0100PA00X+001600Y+010944                       
327GND              U4    -S          A01X+001935Y+010944X0240Y0320R270 S1      
317GND              VIA   -    MD0100PA00X+001600Y+009844X0200Y         S0      
327GND              U3    -S          A01X+001935Y+009844X0240Y0320R270 S1      
317GND              VIA   -    M      A01X+000800Y+011050X0200Y         S2      
017GND              VIA   -    M      A04X+000800Y+011050X0260Y         S2      
017GND                    -    MD0100PA00X+000800Y+011050                       
327GND              R12   -2          A01X+001042Y+011050X0198Y0197R180 S1      
317GND              VIA   -    M      A01X+000800Y+009950X0200Y         S2      
017GND              VIA   -    M      A04X+000800Y+009950X0260Y         S2      
017GND                    -    MD0100PA00X+000800Y+009950                       
327GND              R8    -2          A01X+001042Y+009950X0198Y0197R180 S1      
327GND              U11   -1          A01X+007745Y+008044X0280Y0400R270 S1      
327GND              C8    -2          A01X+011808Y+012600X0198Y0197     S1      
327GND              C13   -2          A01X+011808Y+013000X0198Y0197     S1      
327GND              R42   -2          A01X+014608Y+010400X0198Y0197     S1      
317GND              VIA   -    MD0100PA00X+014850Y+010400X0200Y         S0      
317GND              VIA   -    MD0100PA00X+014850Y+011200X0200Y         S0      
317GND              VIA   -    MD0100PA00X+014850Y+011550X0200Y         S0      
317GND              VIA   -    MD0100PA00X+014850Y+011900X0200Y         S0      
317GND              VIA   -    MD0100PA00X+014850Y+012250X0200Y         S0      
317GND              VIA   -    MD0100PA00X+014850Y+012600X0200Y         S0      
317GND              VIA   -    MD0100PA00X+014850Y+012950X0200Y         S0      
317GND              VIA   -    MD0100PA00X+014850Y+013300X0200Y         S0      
327GND              C16   -2          A01X+014500Y+013450X0400Y0500R180 S1      
327GND              C12   -2          A01X+014500Y+012750X0400Y0500R180 S1      
327GND              C10   -2          A01X+014500Y+012050X0400Y0500R180 S1      
317GND              VIA   -    MD0100PA00X+014850Y+013650X0200Y         S0      
327GND              C9    -2          A01X+014500Y+011350X0400Y0500R180 S1      
317GND              VIA   -    MD0100PA00X+012050Y+012600X0200Y         S0      
317GND              VIA   -    MD0100PA00X+012050Y+013300X0200Y         S0      
317GND              VIA   -    MD0100PA00X+012050Y+012950X0200Y         S0      
317GND              VIA   -    MD0100PA00X+012050Y+013650X0200Y         S0      
327GND              C14   -2          A01X+012400Y+013450X0400Y0500     S1      
327GND              C15   -2          A01X+012400Y+012750X0400Y0500     S1      
327GND              U7    -2          A01X+012157Y+011650X0240Y0380R090 S1      
317GND              VIA   -    MD0100PA00X+011800Y+011650X0200Y         S0      
317GND              H10   -4   MD0220PA00X+012913Y+023274X0300Y    R180 S3      
317GND              H10   -3   MD0220PA00X+011867Y+023708X0300Y    R180 S3      
317GND              H10   -2   MD0220PA00X+011434Y+024754X0300Y    R180 S3      
317GND              H10   -5   MD0220PA00X+013960Y+023708X0300Y    R180 S3      
317GND              H10   -6   MD0220PA00X+014393Y+024754X0300Y    R180 S3      
317GND              H10   -9   MD0220PA00X+011867Y+025801X0300Y    R180 S3      
317GND              H10   -8   MD0220PA00X+012913Y+026234X0300Y    R180 S3      
317GND              H10   -7   MD0220PA00X+013960Y+025801X0300Y    R180 S3      
327GND              VIA   -           A04X+014750Y+017750X0260Y         S2      
327GND              VIA   -           A04X+014000Y+017750X0260Y         S2      
327GND              VIA   -           A04X+013250Y+021500X0260Y         S2      
327GND              VIA   -           A04X+014750Y+020750X0260Y         S2      
327GND              VIA   -           A04X+014000Y+020000X0260Y         S2      
327GND              VIA   -           A04X+014000Y+020750X0260Y         S2      
327GND              VIA   -           A04X+013250Y+020000X0260Y         S2      
327GND              VIA   -           A04X+013250Y+020750X0260Y         S2      
327GND              VIA   -           A04X+014000Y+021500X0260Y         S2      
327GND              VIA   -           A04X+014750Y+021500X0260Y         S2      
327GND              VIA   -           A04X+014750Y+022250X0260Y         S2      
327GND              J1    -A13        A01X+007894Y+028406X0150Y0530     S1      
317GND              VIA   -    MD0100PA00X+008012Y+028820X0200Y    R180 S0      
327GND              J1    -A12        A01X+008130Y+028406X0150Y0530     S1      
327GND              J1    -A10        A01X+008602Y+028406X0150Y0530     S1      
317GND              VIA   -    M      A01X+008484Y+028820X0200Y    R180 S2      
017GND              VIA   -    M      A04X+008484Y+028820X0260Y    R180 S2      
017GND                    -    MD0100PA00X+008484Y+028820                       
327GND              J1    -A11        A01X+008366Y+028406X0150Y0530     S1      
327GND              J1    -A3         A01X+010256Y+028406X0150Y0530     S1      
327GND              J1    -A4         A01X+010020Y+028406X0150Y0530     S1      
317GND              VIA   -    MD0100PA00X+010138Y+028820X0200Y    R180 S0      
327GND              J1    -A2         A01X+010492Y+028406X0150Y0530     S1      
317GND              VIA   -    M      A01X+009311Y+027065X0200Y    R180 S2      
017GND              VIA   -    M      A04X+009311Y+027065X0260Y    R180 S2      
017GND                    -    MD0100PA00X+009311Y+027065                       
327GND              J1    -B10        A01X+008602Y+027480X0150Y0530     S1      
317GND              VIA   -    M      A01X+008602Y+027065X0200Y    R180 S2      
017GND              VIA   -    M      A04X+008602Y+027065X0260Y    R180 S2      
017GND                    -    MD0100PA00X+008602Y+027065                       
327GND              J1    -B13        A01X+007894Y+027480X0150Y0530     S1      
317GND              VIA   -    M      A01X+007894Y+027065X0200Y    R180 S2      
017GND              VIA   -    M      A04X+007894Y+027065X0260Y    R180 S2      
017GND                    -    MD0100PA00X+007894Y+027065                       
327GND              C2    -2   M      A01X+007358Y+026550X0198Y0197     S1      
317GND              VIA   -    MD0100PA00X+007570Y+026390X0200Y         S0      
317GND              VIA   -    MD0100PA00X+007650Y+022750X0200Y         S0      
327GND              R25   -2          A01X+007408Y+022750X0198Y0197     S1      
327GND              R24   -2          A01X+002192Y+024550X0198Y0197R180 S1      
317GND              VIA   -    MD0100PA00X+001950Y+024550X0200Y         S0      
327GND              C6    -2          A01X+002192Y+023750X0198Y0197R180 S1      
317GND              VIA   -    MD0100PA00X+001950Y+023750X0200Y         S0      
317GND              VIA   -    M      A01X+006908Y+024700X0200Y         S2      
017GND              VIA   -    M      A04X+006908Y+024700X0260Y         S2      
017GND                    -    MD0100PA00X+006908Y+024700                       
327GND              C5    -2          A01X+006908Y+024450X0198Y0197     S1      
327GND              J1    -B1         A01X+010728Y+027480X0150Y0530     S1      
327GND              J1    -B4         A01X+010020Y+027480X0150Y0530     S1      
327GND              J1    -B7         A01X+009311Y+027480X0150Y0530     S1      
327GND              J1    -A1         A01X+010728Y+028406X0150Y0530     S1      
327GND              J1    -A7         A01X+009311Y+028406X0150Y0530     S1      
327GND              J1    -A16        A01X+007185Y+028406X0150Y0530     S1      
327GND              J1    -A19        A01X+006476Y+028406X0150Y0530     S1      
317GND              VIA   -    MD0100PA00X+013350Y+016000X0200Y         S0      
317GND              VIA   -    MD0100PA00X+007745Y+007750X0200Y         S0      
327GND              VIA   -           A04X+014750Y+019250X0260Y         S2      
327GND              VIA   -           A04X+014750Y+018500X0260Y         S2      
317GND              VIA   -    MD0100PA00X+010610Y+028820X0200Y    R180 S0      
317GND              VIA   -    MD0100PA00X+007185Y+028820X0200Y         S0      
317GND              VIA   -    MD0100PA00X+010728Y+027065X0200Y         S0      
317GND              VIA   -    MD0100PA00X+010020Y+027065X0200Y         S0      
317GND              J1    -G1  MD0260PA00X+006152Y+032677X0420Y         S3      
317GND              J1    -G4  MD0260PA00X+011053Y+032677X0420Y         S3      
327GND              VIA   -           A04X+014750Y+020000X0260Y         S2      
317GND              VIA   -    MD0100PA00X+005780Y+026390X0200Y         S0      
327GND              C4    -2   M      A01X+005992Y+026550X0198Y0197R180 S1      
317GND              VIA   -    M      A01X+005650Y+026100X0200Y         S2      
017GND              VIA   -    M      A04X+005650Y+026100X0260Y         S2      
017GND                    -    MD0100PA00X+005650Y+026100                       
327GND              C3    -2   M      A01X+005960Y+026100X0280Y0320R090 S1      
317GND              VIA   -    MD0100PA00X+007640Y+025800X0200Y         S0      
327GND              C1    -2   M      A01X+007640Y+026100X0280Y0320R270 S1      
317GND              VIA   -    M      A01X+009311Y+028820X0200Y         S2      
017GND              VIA   -    M      A04X+009311Y+028820X0260Y         S2      
017GND                    -    MD0100PA00X+009311Y+028820                       
317GND              VIA   -    MD0100PA00X+006476Y+028820X0200Y         S0      
327GND              VIA   -           A04X+014000Y+019250X0260Y         S2      
327GND              VIA   -           A04X+013250Y+019250X0260Y         S2      
327GND              VIA   -           A04X+014000Y+018500X0260Y         S2      
317GND              VIA   -    M      A01X+008100Y+000800X0200Y         S2      
017GND              VIA   -    M      A04X+008100Y+000800X0260Y         S2      
017GND                    -    MD0100PA00X+008100Y+000800                       
317GND              VIA   -    M      A01X+013250Y+018500X0200Y         S2      
017GND              VIA   -    M      A04X+013250Y+018500X0260Y         S2      
017GND                    -    MD0100PA00X+013250Y+018500                       
327GND              C7    -2          A01X+012076Y+002721X0198Y0197R180 S1      
327GND              U1    -S          A01X+005959Y+004361X0400Y0560R270 S1      
317GND              VIA   -    M      A01X+005908Y+020400X0200Y         S2      
017GND              VIA   -    M      A04X+005908Y+020400X0260Y         S2      
017GND                    -    MD0100PA00X+005908Y+020400                       
327GND              C11   -2          A01X+005908Y+020150X0198Y0197     S1      
317GND              VIA   -    M      A01X+005959Y+004000X0200Y         S2      
017GND              VIA   -    M      A04X+005959Y+004000X0260Y         S2      
017GND                    -    MD0100PA00X+005959Y+004000                       
327GND              R61   -2          A01X+001392Y+018400X0198Y0197R180 S1      
327GND              R63   -1          A01X+001392Y+020000X0198Y0197     S1      
327GND              R64   -2          A01X+006408Y+019750X0198Y0197     S1      
327GND              R62   -2          A01X+001392Y+019200X0198Y0197R180 S1      
327GND              R37   -2          A01X+014608Y+008000X0198Y0197     S1      
327GND              R38   -2          A01X+014608Y+008800X0198Y0197     S1      
327GND              R39   -2          A01X+014608Y+009600X0198Y0197     S1      
327GND              R26   -2          A01X+002192Y+021350X0198Y0197R180 S1      
327GND              R27   -2          A01X+002192Y+022150X0198Y0197R180 S1      
327GND              R28   -2          A01X+002192Y+022950X0198Y0197R180 S1      
317GND              VIA   -    MD0100PA00X+007738Y+005800X0200Y         S0      
327GND              U2    -S          A01X+007738Y+006171X0400Y0560R090 S1      
317GND              VIA   -    MD0100PA00X+012838Y+008000X0200Y         S0      
327GND              U8    -1          A01X+012838Y+007643X0280Y0400R180 S1      
317GND              VIA   -    MD0100PA00X+008308Y+033615X0200Y         S0      
317GND              VIA   -    MD0100PA00X+006897Y+033614X0200Y         S0      
317GND              VIA   -    MD0100PA00X+014850Y+009600X0200Y         S0      
317GND              VIA   -    MD0100PA00X+014850Y+008000X0200Y         S0      
317GND              VIA   -    MD0100PA00X+014850Y+008800X0200Y         S0      
317GND              VIA   -    M      A01X+004894Y+008950X0200Y         S2      
017GND              VIA   -    M      A04X+004894Y+008950X0260Y         S2      
017GND                    -    MD0100PA00X+004894Y+008950                       
327GND              Q1    -1          A01X+004894Y+009226X0170Y0240     S1      
317GND              VIA   -    M      A01X+005406Y+010250X0200Y         S2      
017GND              VIA   -    M      A04X+005406Y+010250X0260Y         S2      
017GND                    -    MD0100PA00X+005406Y+010250                       
327GND              Q1    -4          A01X+005406Y+009974X0170Y0240     S1      
317GND              VIA   -    M      A01X+006408Y+020000X0200Y         S2      
017GND              VIA   -    M      A04X+006408Y+020000X0260Y         S2      
017GND                    -    MD0100PA00X+006408Y+020000                       
317GND              VIA   -    MD0100PA00X+000734Y+029295X0200Y         S0      
317GND              VIA   -    MD0100PA00X+000735Y+030259X0200Y         S0      
317GND              VIA   -    MD0100PA00X+001680Y+031195X0200Y         S0      
317GND              VIA   -    MD0100PA00X+003570Y+031194X0200Y         S0      
317GND              VIA   -    MD0100PA00X+005140Y+031624X0200Y         S0      
317GND              VIA   -    MD0100PA00X+005360Y+033123X0200Y         S0      
317GND              VIA   -    MD0100PA00X+010308Y+033615X0200Y         S0      
317GND              VIA   -    MD0100PA00X+011687Y+033486X0200Y         S0      
317GND              VIA   -    MD0100PA00X+011846Y+032386X0200Y         S0      
317GND              VIA   -    MD0100PA00X+012972Y+031196X0200Y         S0      
317GND              VIA   -    MD0100PA00X+014456Y+031148X0200Y         S0      
317GND              VIA   -    MD0100PA00X+015170Y+025266X0200Y         S0      
317GND              VIA   -    MD0100PA00X+015170Y+023264X0200Y         S0      
317GND              VIA   -    MD0100PA00X+015166Y+021262X0200Y         S0      
317GND              VIA   -    MD0100PA00X+015166Y+019267X0200Y         S0      
317GND              VIA   -    MD0100PA00X+015170Y+017291X0200Y         S0      
317GND              VIA   -    MD0100PA00X+015168Y+015148X0200Y         S0      
317GND              VIA   -    MD0100PA00X+015168Y+013268X0200Y         S0      
317GND              VIA   -    MD0100PA00X+015168Y+011280X0200Y         S0      
317GND              VIA   -    MD0100PA00X+015168Y+009094X0200Y         S0      
317GND              VIA   -    MD0100PA00X+015171Y+007272X0200Y         S0      
317GND              VIA   -    MD0100PA00X+015169Y+001378X0200Y         S0      
317GND              VIA   -    MD0100PA00X+015033Y+000460X0200Y         S0      
317GND              VIA   -    MD0100PA00X+013694Y+000304X0200Y         S0      
317GND              VIA   -    MD0100PA00X+011719Y+000301X0200Y         S0      
317GND              VIA   -    MD0100PA00X+009850Y+000302X0200Y         S0      
317GND              VIA   -    MD0100PA00X+008070Y+000302X0200Y         S0      
317GND              VIA   -    MD0100PA00X+006087Y+000301X0200Y         S0      
317GND              VIA   -    MD0100PA00X+004618Y+000301X0200Y         S0      
317GND              VIA   -    MD0100PA00X+000519Y+000384X0200Y         S0      
317GND              VIA   -    MD0100PA00X+002703Y+000302X0200Y         S0      
317GND              VIA   -    MD0100PA00X+000300Y+009086X0200Y         S0      
317GND              VIA   -    MD0100PA00X+000300Y+010647X0200Y         S0      
317GND              VIA   -    MD0100PA00X+000300Y+012647X0200Y         S0      
317GND              VIA   -    MD0100PA00X+000300Y+014647X0200Y         S0      
317GND              VIA   -    MD0100PA00X+000300Y+016647X0200Y         S0      
317GND              VIA   -    MD0100PA00X+000300Y+018647X0200Y         S0      
317GND              VIA   -    MD0100PA00X+000300Y+020647X0200Y         S0      
317GND              VIA   -    MD0100PA00X+000300Y+022647X0200Y         S0      
317GND              VIA   -    MD0100PA00X+000300Y+024647X0200Y         S0      
317GND              J1    -G3  MD0260PA00X+011053Y+031496X0420Y         S3      
317GND              J1    -G2  MD0260PA00X+006152Y+031496X0420Y         S3      
327GND              U5    -12         A01X+003648Y+021353X0240Y0540R270 S1      
317GND              VIA   -    M      A01X+004100Y+021353X0200Y         S2      
017GND              VIA   -    M      A04X+004100Y+021353X0260Y         S2      
017GND                    -    MD0100PA00X+004100Y+021353                       
317GND              VIA   -    MD0100PA00X+001950Y+022950X0200Y         S0      
317GND              VIA   -    M      A01X+001950Y+021350X0200Y         S2      
017GND              VIA   -    M      A04X+001950Y+021350X0260Y         S2      
017GND                    -    MD0100PA00X+001950Y+021350                       
317GND              VIA   -    M      A01X+001950Y+022150X0200Y         S2      
017GND              VIA   -    M      A04X+001950Y+022150X0260Y         S2      
017GND                    -    MD0100PA00X+001950Y+022150                       
327GND              U9    -4          A01X+002857Y+018600X0240Y0560R270 S1      
317GND              VIA   -    M      A01X+003300Y+018600X0200Y         S2      
017GND              VIA   -    M      A04X+003300Y+018600X0260Y         S2      
017GND                    -    MD0100PA00X+003300Y+018600                       
317GND              VIA   -    M      A01X+001150Y+018400X0200Y         S2      
017GND              VIA   -    M      A04X+001150Y+018400X0260Y         S2      
017GND                    -    MD0100PA00X+001150Y+018400                       
317GND              VIA   -    M      A01X+001150Y+019200X0200Y         S2      
017GND              VIA   -    M      A04X+001150Y+019200X0260Y         S2      
017GND                    -    MD0100PA00X+001150Y+019200                       
317GND              VIA   -    M      A01X+001150Y+020000X0200Y         S2      
017GND              VIA   -    M      A04X+001150Y+020000X0260Y         S2      
017GND                    -    MD0100PA00X+001150Y+020000                       
317GND              VIA   -    M      A01X+011318Y+003170X0200Y         S2      
017GND              VIA   -    M      A04X+011318Y+003170X0260Y         S2      
017GND                    -    MD0100PA00X+011318Y+003170                       
327GND              U6    -4          A01X+012298Y+000672X0240Y0520R270 S1      
317GND              VIA   -    M      A01X+011850Y+000672X0200Y         S2      
017GND              VIA   -    M      A04X+011850Y+000672X0260Y         S2      
017GND                    -    MD0100PA00X+011850Y+000672                       
327GND              J1    -B16        A01X+007185Y+027480X0150Y0530     S1      
327GND              J1    -B19        A01X+006476Y+027480X0150Y0530     S1      
317USB2_DEBUG_DN    J2    -2    D0280PA00X+009488Y+007216X0440Y         S3      
327USB2_DEBUG_DN    R51   -2   M      A01X+012278Y+009212X0180Y0200R090 S1      
327USB2_DEBUG_DN    U8    -3   M      A01X+012051Y+008312X0240Y0280R090 S1      
327USB2_DEBUG_DN    L1    -2   M      A01X+012278Y+009058X0140Y0360     S1      
317USB2_DEBUG_DP    J2    -3    D0280PA00X+009488Y+006429X0440Y         S3      
327USB2_DEBUG_DP    R52   -2   M      A01X+012612Y+009212X0180Y0200R090 S1      
327USB2_DEBUG_DP    U8    -2   M      A01X+012838Y+008312X0240Y0280R090 S1      
327USB2_DEBUG_DP    L1    -3   M      A01X+012612Y+009058X0140Y0360     S1      
327m0021            R3    -2          A01X+007676Y+003944X0440Y0540R090 S1      
317m0021            D1    -1   MD0380PA00X+007748Y+002630X0540Y0540     S3      
327m0021            U2    -D          A01X+006872Y+005797X0400Y0560R090 S1      
317m0021            VIA   -    M      A01X+006872Y+005400X0200Y         S2      
017m0021            VIA   -    M      A04X+006872Y+005400X0260Y         S2      
017m0021                  -    MD0100PA00X+006872Y+005400                       
327m0022            R4    -2          A01X+007008Y+006750X0198Y0197     S1      
317m0022            VIA   -    M      A01X+007008Y+006450X0200Y         S2      
017m0022            VIA   -    M      A04X+007008Y+006450X0260Y         S2      
017m0022                  -    MD0100PA00X+007008Y+006450                       
327m0022            U2    -G          A01X+007738Y+005423X0400Y0560R090 S1      
317m0023            D1    -3    D0380PA00X+005748Y+002630X0540Y         S3      
327m0023            U1    -D          A01X+006825Y+004735X0400Y0560R270 S1      
327m0023            R1    -2   M      A01X+006940Y+003710X0280Y0320R270 S1      
327m0024            R2    -2          A01X+005950Y+005742X0198Y0197R270 S1      
327m0024            U1    -G          A01X+005959Y+005109X0400Y0560R270 S1      
317m0024            VIA   -    M      A01X+005950Y+005500X0200Y         S2      
017m0024            VIA   -    M      A04X+005950Y+005500X0260Y         S2      
017m0024                  -    MD0100PA00X+005950Y+005500                       
327m0025            R4    -1          A01X+006692Y+006750X0198Y0197     S1      
317m0025            VIA   -    M      A01X+008173Y+007777X0200Y         S2      
017m0025            VIA   -    M      A04X+008173Y+007777X0260Y         S2      
017m0025                  -    MD0100PA00X+008173Y+007777                       
317m0025            VIA   -    MD0100PA00X+006692Y+007000X0200Y         S0      
327m0025            J1    -B6         A01X+009547Y+027480X0150Y0530     S1      
317m0026            VIA   -    MD0100PA00X+006450Y+006350X0200Y         S0      
327m0026            R2    -1          A01X+005950Y+006058X0198Y0197R270 S1      
317m0026            VIA   -    MD0100PA00X+008450Y+007650X0200Y         S0      
327m0026            VIA   -    M      A01X+008900Y+012800X0300Y         S1      
327m0026            J1    -B5         A01X+009784Y+027480X0150Y0530     S1      
C                                                                               
C  ****************************************                                     
C      DUMMY NET PINS & VIAS ON THE BOARD                                       
C  ****************************************                                     
C                                                                               
317N/C              H12   -1    D1190UA00X+002598Y+027945X1190Y    R180 S3      
317N/C              H11   -1    D1190UA00X+013622Y+004342X1190Y    R180 S3      
327N/C                    -           A01X+010500Y+023450X0390Y         S1      
327N/C                    -           A01X+001149Y+008588X0390Y         S1      
327N/C                    -           A01X+005100Y+030100X0390Y         S1      
327N/C              U5    -18         A01X+005952Y+022672X0160Y0540R270 S1      
327N/C              U5    -17         A01X+005952Y+022416X0160Y0540R270 S1      
327N/C              U5    -16         A01X+005952Y+022160X0160Y0540R270 S1      
327N/C              U5    -15         A01X+005952Y+021904X0160Y0540R270 S1      
327N/C              U5    -14         A01X+005952Y+021648X0160Y0540R270 S1      
327N/C              U5    -13         A01X+005952Y+021353X0240Y0540R270 S1      
327N/C              U5    -8          A01X+003648Y+022416X0160Y0540R270 S1      
327N/C              U5    -7          A01X+003648Y+022672X0160Y0540R270 S1      
327N/C              U5    -6          A01X+003648Y+022928X0160Y0540R270 S1      
327N/C              U5    -5          A01X+003648Y+023184X0160Y0540R270 S1      
327N/C              U5    -4          A01X+003648Y+023440X0160Y0540R270 S1      
327N/C              U5    -1          A01X+003648Y+024247X0240Y0540R270 S1      
317N/C              J1    -H1   D0520UA00X+010787Y+029468X0520Y         S3      
317N/C              J1    -H2   D0520UA00X+006417Y+029468X0520Y         S3      
317N/C              H4    -1    D1250UA00X+001400Y+025550X1250Y         S3      
317N/C              H3    -1    D1250UA00X+013402Y+014793X1250Y         S3      
317N/C              H2    -1    D1250UA00X+006099Y+013191X1250Y         S3      
317N/C              H9    -1    D1580UA00X+002402Y+005866X1580Y    R180 S3      
317N/C              H10   -1    D1580UA00X+012913Y+024754X1580Y    R180 S3      
C                                                                               
C  ****************************************                                     
C      TOOLING HOLE PINS ON THE BOARD                                           
C  ****************************************                                     
C                                                                               
367                       -     D0410UA00X+034050Y+044515X0410Y         S3      
367                       -     D0410UA00X+035050Y+044515X0410Y         S3      
367                       -     D0410UA00X+034050Y+042015X0410Y         S3      
367                       -     D0410UA00X+035050Y+042015X0410Y         S3      
367                       -     D0410UA00X+035050Y+059735X0410Y    R180 S3      
367                       -     D0410UA00X+034050Y+059735X0410Y    R180 S3      
367                       -     D0410UA00X+035050Y+062235X0410Y    R180 S3      
367                       -     D0410UA00X+034050Y+062235X0410Y    R180 S3      
367                       -     D0410UA00X+038000Y+059735X0410Y    R180 S3      
367                       -     D0410UA00X+037000Y+059735X0410Y    R180 S3      
367                       -     D0410UA00X+038000Y+062235X0410Y    R180 S3      
367                       -     D0410UA00X+037000Y+062235X0410Y    R180 S3      
367                       -     D0410UA00X+037000Y+034134X0410Y         S3      
367                       -     D0410UA00X+038000Y+034134X0410Y         S3      
367                       -     D0410UA00X+037000Y+031634X0410Y         S3      
367                       -     D0410UA00X+038000Y+031634X0410Y         S3      
C                                                                               
C  End-of-Job                                                                   
C                                                                               
999                                                                             
